(kicad_pcb
	(version 20260206)
	(generator "pcbnew")
	(generator_version "10.0")
	(general
		(thickness 1.6)
		(legacy_teardrops no)
	)
	(paper "A4")
	(title_block
		(title "04192023_DAF0TMB3IC0_F0TG_MB_C_brd_V02_OCP.brd")
		(comment 1 "Grand Teton / footprints 4144-4149 of 8354")
	)
	(layers
		(0 "F.Cu" signal "TOP")
		(4 "In1.Cu" signal "GND")
		(6 "In2.Cu" signal "IN1")
		(8 "In3.Cu" signal "GND1")
		(10 "In4.Cu" signal "IN2")
		(12 "In5.Cu" signal "GND2")
		(14 "In6.Cu" signal "IN3")
		(16 "In7.Cu" signal "GND3")
		(18 "In8.Cu" signal "VCC")
		(20 "In9.Cu" signal "VCC1")
		(22 "In10.Cu" signal "GND4")
		(24 "In11.Cu" signal "IN4")
		(26 "In12.Cu" signal "GND5")
		(28 "In13.Cu" signal "IN5")
		(30 "In14.Cu" signal "GND6")
		(32 "In15.Cu" signal "IN6")
		(34 "In16.Cu" signal "GND7")
		(2 "B.Cu" signal "BOTTOM")
		(9 "F.Adhes" user "F.Adhesive")
		(11 "B.Adhes" user "B.Adhesive")
		(13 "F.Paste" user "Package Geometry/Pastemask Top")
		(15 "B.Paste" user "Package Geometry/Pastemask Bottom")
		(5 "F.SilkS" user "Ref Des/Silkscreen Top")
		(7 "B.SilkS" user "Ref Des/Silkscreen Bottom")
		(1 "F.Mask" user "Board Geometry/Soldermask Top")
		(3 "B.Mask" user "Board Geometry/Soldermask Bottom")
		(17 "Dwgs.User" user "User.Drawings")
		(19 "Cmts.User" user "User.Comments")
		(21 "Eco1.User" user "User.Eco1")
		(23 "Eco2.User" user "User.Eco2")
		(25 "Edge.Cuts" user "Board Geometry/Outline")
		(27 "Margin" user)
		(31 "F.CrtYd" user "Package Geometry/Place Bound Top")
		(29 "B.CrtYd" user "Package Geometry/Place Bound Bottom")
		(35 "F.Fab" user "Ref Des/Assembly Top")
		(33 "B.Fab" user "Ref Des/Assembly Bottom")
	)
	(footprint ""
		(layer "F.Cu")
		(at 331.156564 -138.890502 89.946)
		(property "Reference" "PR470"
			(at 0 0 89.946)
			(layer "F.SilkS")
			(hide yes)
			(effects
				(font
					(size 1.27 1.27)
				)
			)
		)
		(property "Value" ""
			(at 0 0 89.946)
			(layer "F.Fab")
			(effects
				(font
					(size 1.27 1.27)
				)
			)
		)
		(duplicate_pad_numbers_are_jumpers no)
		(fp_line
			(start -0.787275 -0.40642)
			(end 0.787525 -0.40638)
			(stroke
				(width 0.1524)
				(type default)
			)
			(layer "F.SilkS")
		)
		(fp_line
			(start 0.787525 -0.40638)
			(end 0.787275 0.40642)
			(stroke
				(width 0.1524)
				(type default)
			)
			(layer "F.SilkS")
		)
		(fp_line
			(start -0.787525 0.40638)
			(end -0.787275 -0.40642)
			(stroke
				(width 0.1524)
				(type default)
			)
			(layer "F.SilkS")
		)
		(fp_line
			(start 0.787275 0.40642)
			(end -0.787525 0.40638)
			(stroke
				(width 0.1524)
				(type default)
			)
			(layer "F.SilkS")
		)
		(fp_line
			(start -0.679484 -0.305176)
			(end -0.120683 -0.30494)
			(stroke
				(width 0.1)
				(type default)
			)
			(layer "F.Fab")
		)
		(fp_line
			(start -0.120683 -0.30494)
			(end -0.120659 -0.279286)
			(stroke
				(width 0.1)
				(type default)
			)
			(layer "F.Fab")
		)
		(fp_line
			(start 0.120617 -0.304914)
			(end 0.679417 -0.304678)
			(stroke
				(width 0.1)
				(type default)
			)
			(layer "F.Fab")
		)
		(fp_line
			(start 0.679417 -0.304678)
			(end 0.679484 0.304922)
			(stroke
				(width 0.1)
				(type default)
			)
			(layer "F.Fab")
		)
		(fp_line
			(start 0.120641 -0.279514)
			(end 0.120617 -0.304914)
			(stroke
				(width 0.1)
				(type default)
			)
			(layer "F.Fab")
		)
		(fp_line
			(start -0.120659 -0.279286)
			(end 0.120641 -0.279514)
			(stroke
				(width 0.1)
				(type default)
			)
			(layer "F.Fab")
		)
		(fp_line
			(start 0.120405 0.279287)
			(end -0.120641 0.279514)
			(stroke
				(width 0.1)
				(type default)
			)
			(layer "F.Fab")
		)
		(fp_line
			(start -0.120641 0.279514)
			(end -0.120617 0.304914)
			(stroke
				(width 0.1)
				(type default)
			)
			(layer "F.Fab")
		)
		(fp_line
			(start -0.679417 0.304678)
			(end -0.679484 -0.305176)
			(stroke
				(width 0.1)
				(type default)
			)
			(layer "F.Fab")
		)
		(fp_line
			(start 0.120429 0.304687)
			(end 0.120405 0.279287)
			(stroke
				(width 0.1)
				(type default)
			)
			(layer "F.Fab")
		)
		(fp_line
			(start -0.120617 0.304914)
			(end -0.679417 0.304678)
			(stroke
				(width 0.1)
				(type default)
			)
			(layer "F.Fab")
		)
		(fp_line
			(start 0.679484 0.304922)
			(end 0.120429 0.304687)
			(stroke
				(width 0.1)
				(type default)
			)
			(layer "F.Fab")
		)
		(pad "1" smd circle
			(at -0.40005 0 89.946)
			(size 0 0)
			(layers "F.Cu" "F.Mask" "F.Paste")
			(net "PVDD18_S5_P0_FB")
		)
		(pad "2" smd circle
			(at 0.40005 0 89.946)
			(size 0 0)
			(layers "F.Cu" "F.Mask" "F.Paste")
			(net "PVDD18_S5_P0_RGND")
		)
	)
	(footprint ""
		(layer "F.Cu")
		(at 119.135652 -76.743052 90)
		(property "Reference" "PC6011"
			(at 0 0 90)
			(layer "F.SilkS")
			(hide yes)
			(effects
				(font
					(size 1.27 1.27)
				)
			)
		)
		(property "Value" ""
			(at 0 0 90)
			(layer "F.Fab")
			(effects
				(font
					(size 1.27 1.27)
				)
			)
		)
		(duplicate_pad_numbers_are_jumpers no)
		(fp_line
			(start 0.7874 -0.4064)
			(end 0.7874 0.4064)
			(stroke
				(width 0.1524)
				(type default)
			)
			(layer "F.SilkS")
		)
		(fp_line
			(start -0.7874 -0.4064)
			(end 0.7874 -0.4064)
			(stroke
				(width 0.1524)
				(type default)
			)
			(layer "F.SilkS")
		)
		(fp_line
			(start 0.7874 0.4064)
			(end -0.7874 0.4064)
			(stroke
				(width 0.1524)
				(type default)
			)
			(layer "F.SilkS")
		)
		(fp_line
			(start -0.7874 0.4064)
			(end -0.7874 -0.4064)
			(stroke
				(width 0.1524)
				(type default)
			)
			(layer "F.SilkS")
		)
		(fp_line
			(start -0.12065 -0.305054)
			(end -0.12065 -0.2794)
			(stroke
				(width 0.1)
				(type default)
			)
			(layer "F.Fab")
		)
		(fp_line
			(start -0.67945 -0.305054)
			(end -0.12065 -0.305054)
			(stroke
				(width 0.1)
				(type default)
			)
			(layer "F.Fab")
		)
		(fp_line
			(start 0.67945 -0.3048)
			(end 0.67945 0.3048)
			(stroke
				(width 0.1)
				(type default)
			)
			(layer "F.Fab")
		)
		(fp_line
			(start 0.12065 -0.3048)
			(end 0.67945 -0.3048)
			(stroke
				(width 0.1)
				(type default)
			)
			(layer "F.Fab")
		)
		(fp_line
			(start 0.12065 -0.2794)
			(end 0.12065 -0.3048)
			(stroke
				(width 0.1)
				(type default)
			)
			(layer "F.Fab")
		)
		(fp_line
			(start -0.12065 -0.2794)
			(end 0.12065 -0.2794)
			(stroke
				(width 0.1)
				(type default)
			)
			(layer "F.Fab")
		)
		(fp_line
			(start 0.120396 0.2794)
			(end -0.12065 0.2794)
			(stroke
				(width 0.1)
				(type default)
			)
			(layer "F.Fab")
		)
		(fp_line
			(start -0.12065 0.2794)
			(end -0.12065 0.3048)
			(stroke
				(width 0.1)
				(type default)
			)
			(layer "F.Fab")
		)
		(fp_line
			(start 0.67945 0.3048)
			(end 0.120396 0.3048)
			(stroke
				(width 0.1)
				(type default)
			)
			(layer "F.Fab")
		)
		(fp_line
			(start 0.120396 0.3048)
			(end 0.120396 0.2794)
			(stroke
				(width 0.1)
				(type default)
			)
			(layer "F.Fab")
		)
		(fp_line
			(start -0.12065 0.3048)
			(end -0.67945 0.3048)
			(stroke
				(width 0.1)
				(type default)
			)
			(layer "F.Fab")
		)
		(fp_line
			(start -0.67945 0.3048)
			(end -0.67945 -0.305054)
			(stroke
				(width 0.1)
				(type default)
			)
			(layer "F.Fab")
		)
		(pad "1" smd circle
			(at -0.40005 0 90)
			(size 0 0)
			(layers "F.Cu" "F.Mask" "F.Paste")
			(net "SW_P12V_AUX_P1V2_AUX_FLT")
		)
		(pad "2" smd circle
			(at 0.40005 0 90)
			(size 0 0)
			(layers "F.Cu" "F.Mask" "F.Paste")
			(net "GND")
		)
	)
	(footprint ""
		(layer "F.Cu")
		(at 204.7621 -398.940782 180)
		(property "Reference" "PC2348"
			(at 0 0 180)
			(layer "F.SilkS")
			(hide yes)
			(effects
				(font
					(size 1.27 1.27)
				)
			)
		)
		(property "Value" ""
			(at 0 0 180)
			(layer "F.Fab")
			(effects
				(font
					(size 1.27 1.27)
				)
			)
		)
		(duplicate_pad_numbers_are_jumpers no)
		(fp_line
			(start 0.7874 0.4064)
			(end -0.7874 0.4064)
			(stroke
				(width 0.1524)
				(type default)
			)
			(layer "F.SilkS")
		)
		(fp_line
			(start 0.7874 -0.4064)
			(end 0.7874 0.4064)
			(stroke
				(width 0.1524)
				(type default)
			)
			(layer "F.SilkS")
		)
		(fp_line
			(start -0.7874 0.4064)
			(end -0.7874 -0.4064)
			(stroke
				(width 0.1524)
				(type default)
			)
			(layer "F.SilkS")
		)
		(fp_line
			(start -0.7874 -0.4064)
			(end 0.7874 -0.4064)
			(stroke
				(width 0.1524)
				(type default)
			)
			(layer "F.SilkS")
		)
		(fp_line
			(start 0.67945 0.3048)
			(end 0.120396 0.3048)
			(stroke
				(width 0.1)
				(type default)
			)
			(layer "F.Fab")
		)
		(fp_line
			(start 0.67945 -0.3048)
			(end 0.67945 0.3048)
			(stroke
				(width 0.1)
				(type default)
			)
			(layer "F.Fab")
		)
		(fp_line
			(start 0.12065 -0.2794)
			(end 0.12065 -0.3048)
			(stroke
				(width 0.1)
				(type default)
			)
			(layer "F.Fab")
		)
		(fp_line
			(start 0.12065 -0.3048)
			(end 0.67945 -0.3048)
			(stroke
				(width 0.1)
				(type default)
			)
			(layer "F.Fab")
		)
		(fp_line
			(start 0.120396 0.3048)
			(end 0.120396 0.2794)
			(stroke
				(width 0.1)
				(type default)
			)
			(layer "F.Fab")
		)
		(fp_line
			(start 0.120396 0.2794)
			(end -0.12065 0.2794)
			(stroke
				(width 0.1)
				(type default)
			)
			(layer "F.Fab")
		)
		(fp_line
			(start -0.12065 0.3048)
			(end -0.67945 0.3048)
			(stroke
				(width 0.1)
				(type default)
			)
			(layer "F.Fab")
		)
		(fp_line
			(start -0.12065 0.2794)
			(end -0.12065 0.3048)
			(stroke
				(width 0.1)
				(type default)
			)
			(layer "F.Fab")
		)
		(fp_line
			(start -0.12065 -0.2794)
			(end 0.12065 -0.2794)
			(stroke
				(width 0.1)
				(type default)
			)
			(layer "F.Fab")
		)
		(fp_line
			(start -0.12065 -0.305054)
			(end -0.12065 -0.2794)
			(stroke
				(width 0.1)
				(type default)
			)
			(layer "F.Fab")
		)
		(fp_line
			(start -0.67945 0.3048)
			(end -0.67945 -0.305054)
			(stroke
				(width 0.1)
				(type default)
			)
			(layer "F.Fab")
		)
		(fp_line
			(start -0.67945 -0.305054)
			(end -0.12065 -0.305054)
			(stroke
				(width 0.1)
				(type default)
			)
			(layer "F.Fab")
		)
		(pad "1" smd circle
			(at -0.40005 0 180)
			(size 0 0)
			(layers "F.Cu" "F.Mask" "F.Paste")
			(net "HSC_OCREF")
		)
		(pad "2" smd circle
			(at 0.40005 0 180)
			(size 0 0)
			(layers "F.Cu" "F.Mask" "F.Paste")
			(net "AGND_HSC")
		)
	)
	(footprint ""
		(layer "F.Cu")
		(at 264.478516 -132.352796 180)
		(property "Reference" "R6098"
			(at 0 0 180)
			(layer "F.SilkS")
			(hide yes)
			(effects
				(font
					(size 1.27 1.27)
				)
			)
		)
		(property "Value" ""
			(at 0 0 180)
			(layer "F.Fab")
			(effects
				(font
					(size 1.27 1.27)
				)
			)
		)
		(duplicate_pad_numbers_are_jumpers no)
		(fp_line
			(start 0.7874 0.4064)
			(end -0.7874 0.4064)
			(stroke
				(width 0.1524)
				(type default)
			)
			(layer "F.SilkS")
		)
		(fp_line
			(start 0.7874 -0.4064)
			(end 0.7874 0.4064)
			(stroke
				(width 0.1524)
				(type default)
			)
			(layer "F.SilkS")
		)
		(fp_line
			(start -0.7874 0.4064)
			(end -0.7874 -0.4064)
			(stroke
				(width 0.1524)
				(type default)
			)
			(layer "F.SilkS")
		)
		(fp_line
			(start -0.7874 -0.4064)
			(end 0.7874 -0.4064)
			(stroke
				(width 0.1524)
				(type default)
			)
			(layer "F.SilkS")
		)
		(fp_line
			(start 0.67945 0.3048)
			(end 0.120396 0.3048)
			(stroke
				(width 0.1)
				(type default)
			)
			(layer "F.Fab")
		)
		(fp_line
			(start 0.67945 -0.3048)
			(end 0.67945 0.3048)
			(stroke
				(width 0.1)
				(type default)
			)
			(layer "F.Fab")
		)
		(fp_line
			(start 0.12065 -0.2794)
			(end 0.12065 -0.3048)
			(stroke
				(width 0.1)
				(type default)
			)
			(layer "F.Fab")
		)
		(fp_line
			(start 0.12065 -0.3048)
			(end 0.67945 -0.3048)
			(stroke
				(width 0.1)
				(type default)
			)
			(layer "F.Fab")
		)
		(fp_line
			(start 0.120396 0.3048)
			(end 0.120396 0.2794)
			(stroke
				(width 0.1)
				(type default)
			)
			(layer "F.Fab")
		)
		(fp_line
			(start 0.120396 0.2794)
			(end -0.12065 0.2794)
			(stroke
				(width 0.1)
				(type default)
			)
			(layer "F.Fab")
		)
		(fp_line
			(start -0.12065 0.3048)
			(end -0.67945 0.3048)
			(stroke
				(width 0.1)
				(type default)
			)
			(layer "F.Fab")
		)
		(fp_line
			(start -0.12065 0.2794)
			(end -0.12065 0.3048)
			(stroke
				(width 0.1)
				(type default)
			)
			(layer "F.Fab")
		)
		(fp_line
			(start -0.12065 -0.2794)
			(end 0.12065 -0.2794)
			(stroke
				(width 0.1)
				(type default)
			)
			(layer "F.Fab")
		)
		(fp_line
			(start -0.12065 -0.305054)
			(end -0.12065 -0.2794)
			(stroke
				(width 0.1)
				(type default)
			)
			(layer "F.Fab")
		)
		(fp_line
			(start -0.67945 0.3048)
			(end -0.67945 -0.305054)
			(stroke
				(width 0.1)
				(type default)
			)
			(layer "F.Fab")
		)
		(fp_line
			(start -0.67945 -0.305054)
			(end -0.12065 -0.305054)
			(stroke
				(width 0.1)
				(type default)
			)
			(layer "F.Fab")
		)
		(pad "1" smd circle
			(at -0.40005 0 180)
			(size 0 0)
			(layers "F.Cu" "F.Mask" "F.Paste")
			(net "GND")
		)
		(pad "2" smd circle
			(at 0.40005 0 180)
			(size 0 0)
			(layers "F.Cu" "F.Mask" "F.Paste")
			(net "SPI_CPU0_CLK")
		)
	)
	(footprint ""
		(layer "F.Cu")
		(at 215.330278 -128.804924)
		(property "Reference" "R214"
			(at 0 0 0)
			(layer "F.SilkS")
			(hide yes)
			(effects
				(font
					(size 1.27 1.27)
				)
			)
		)
		(property "Value" ""
			(at 0 0 0)
			(layer "F.Fab")
			(effects
				(font
					(size 1.27 1.27)
				)
			)
		)
		(duplicate_pad_numbers_are_jumpers no)
		(fp_line
			(start -0.7874 -0.4064)
			(end 0.7874 -0.4064)
			(stroke
				(width 0.1524)
				(type default)
			)
			(layer "F.SilkS")
		)
		(fp_line
			(start -0.7874 0.4064)
			(end -0.7874 -0.4064)
			(stroke
				(width 0.1524)
				(type default)
			)
			(layer "F.SilkS")
		)
		(fp_line
			(start 0.7874 -0.4064)
			(end 0.7874 0.4064)
			(stroke
				(width 0.1524)
				(type default)
			)
			(layer "F.SilkS")
		)
		(fp_line
			(start 0.7874 0.4064)
			(end -0.7874 0.4064)
			(stroke
				(width 0.1524)
				(type default)
			)
			(layer "F.SilkS")
		)
		(fp_line
			(start -0.67945 -0.305054)
			(end -0.12065 -0.305054)
			(stroke
				(width 0.1)
				(type default)
			)
			(layer "F.Fab")
		)
		(fp_line
			(start -0.67945 0.3048)
			(end -0.67945 -0.305054)
			(stroke
				(width 0.1)
				(type default)
			)
			(layer "F.Fab")
		)
		(fp_line
			(start -0.12065 -0.305054)
			(end -0.12065 -0.2794)
			(stroke
				(width 0.1)
				(type default)
			)
			(layer "F.Fab")
		)
		(fp_line
			(start -0.12065 -0.2794)
			(end 0.12065 -0.2794)
			(stroke
				(width 0.1)
				(type default)
			)
			(layer "F.Fab")
		)
		(fp_line
			(start -0.12065 0.2794)
			(end -0.12065 0.3048)
			(stroke
				(width 0.1)
				(type default)
			)
			(layer "F.Fab")
		)
		(fp_line
			(start -0.12065 0.3048)
			(end -0.67945 0.3048)
			(stroke
				(width 0.1)
				(type default)
			)
			(layer "F.Fab")
		)
		(fp_line
			(start 0.120396 0.2794)
			(end -0.12065 0.2794)
			(stroke
				(width 0.1)
				(type default)
			)
			(layer "F.Fab")
		)
		(fp_line
			(start 0.120396 0.3048)
			(end 0.120396 0.2794)
			(stroke
				(width 0.1)
				(type default)
			)
			(layer "F.Fab")
		)
		(fp_line
			(start 0.12065 -0.3048)
			(end 0.67945 -0.3048)
			(stroke
				(width 0.1)
				(type default)
			)
			(layer "F.Fab")
		)
		(fp_line
			(start 0.12065 -0.2794)
			(end 0.12065 -0.3048)
			(stroke
				(width 0.1)
				(type default)
			)
			(layer "F.Fab")
		)
		(fp_line
			(start 0.67945 -0.3048)
			(end 0.67945 0.3048)
			(stroke
				(width 0.1)
				(type default)
			)
			(layer "F.Fab")
		)
		(fp_line
			(start 0.67945 0.3048)
			(end 0.120396 0.3048)
			(stroke
				(width 0.1)
				(type default)
			)
			(layer "F.Fab")
		)
		(pad "1" smd circle
			(at -0.40005 0)
			(size 0 0)
			(layers "F.Cu" "F.Mask" "F.Paste")
			(net "PWRGD_P1V8_AUX")
		)
		(pad "2" smd circle
			(at 0.40005 0)
			(size 0 0)
			(layers "F.Cu" "F.Mask" "F.Paste")
			(net "PWRGD_P1V8_AUX_R")
		)
	)
	(footprint ""
		(layer "F.Cu")
		(at 73.303638 -55.122826 -90)
		(property "Reference" "R1177"
			(at 0 0 270)
			(layer "F.SilkS")
			(hide yes)
			(effects
				(font
					(size 1.27 1.27)
				)
			)
		)
		(property "Value" ""
			(at 0 0 270)
			(layer "F.Fab")
			(effects
				(font
					(size 1.27 1.27)
				)
			)
		)
		(duplicate_pad_numbers_are_jumpers no)
		(fp_line
			(start -0.7874 0.4064)
			(end -0.7874 -0.4064)
			(stroke
				(width 0.1524)
				(type default)
			)
			(layer "F.SilkS")
		)
		(fp_line
			(start 0.7874 0.4064)
			(end -0.7874 0.4064)
			(stroke
				(width 0.1524)
				(type default)
			)
			(layer "F.SilkS")
		)
		(fp_line
			(start -0.7874 -0.4064)
			(end 0.7874 -0.4064)
			(stroke
				(width 0.1524)
				(type default)
			)
			(layer "F.SilkS")
		)
		(fp_line
			(start 0.7874 -0.4064)
			(end 0.7874 0.4064)
			(stroke
				(width 0.1524)
				(type default)
			)
			(layer "F.SilkS")
		)
		(fp_line
			(start -0.67945 0.3048)
			(end -0.67945 -0.305054)
			(stroke
				(width 0.1)
				(type default)
			)
			(layer "F.Fab")
		)
		(fp_line
			(start -0.12065 0.3048)
			(end -0.67945 0.3048)
			(stroke
				(width 0.1)
				(type default)
			)
			(layer "F.Fab")
		)
		(fp_line
			(start 0.120396 0.3048)
			(end 0.120396 0.2794)
			(stroke
				(width 0.1)
				(type default)
			)
			(layer "F.Fab")
		)
		(fp_line
			(start 0.67945 0.3048)
			(end 0.120396 0.3048)
			(stroke
				(width 0.1)
				(type default)
			)
			(layer "F.Fab")
		)
		(fp_line
			(start -0.12065 0.2794)
			(end -0.12065 0.3048)
			(stroke
				(width 0.1)
				(type default)
			)
			(layer "F.Fab")
		)
		(fp_line
			(start 0.120396 0.2794)
			(end -0.12065 0.2794)
			(stroke
				(width 0.1)
				(type default)
			)
			(layer "F.Fab")
		)
		(fp_line
			(start -0.12065 -0.2794)
			(end 0.12065 -0.2794)
			(stroke
				(width 0.1)
				(type default)
			)
			(layer "F.Fab")
		)
		(fp_line
			(start 0.12065 -0.2794)
			(end 0.12065 -0.3048)
			(stroke
				(width 0.1)
				(type default)
			)
			(layer "F.Fab")
		)
		(fp_line
			(start 0.12065 -0.3048)
			(end 0.67945 -0.3048)
			(stroke
				(width 0.1)
				(type default)
			)
			(layer "F.Fab")
		)
		(fp_line
			(start 0.67945 -0.3048)
			(end 0.67945 0.3048)
			(stroke
				(width 0.1)
				(type default)
			)
			(layer "F.Fab")
		)
		(fp_line
			(start -0.67945 -0.305054)
			(end -0.12065 -0.305054)
			(stroke
				(width 0.1)
				(type default)
			)
			(layer "F.Fab")
		)
		(fp_line
			(start -0.12065 -0.305054)
			(end -0.12065 -0.2794)
			(stroke
				(width 0.1)
				(type default)
			)
			(layer "F.Fab")
		)
		(pad "1" smd circle
			(at -0.40005 0 270)
			(size 0 0)
			(layers "F.Cu" "F.Mask" "F.Paste")
			(net "RST_PERST_OCP_V3_2_BUF_R_N")
		)
		(pad "2" smd circle
			(at 0.40005 0 270)
			(size 0 0)
			(layers "F.Cu" "F.Mask" "F.Paste")
			(net "RST_PERST_OCP_V3_2_BUF_N")
		)
	)
)
